(kicad_pcb
	(version 20260206)
	(generator "pcbnew")
	(generator_version "10.0")
	(general
		(thickness 1.6)
		(legacy_teardrops no)
	)
	(paper "A4")
	(title_block
		(title "panther-plus-userver — 13130-1b_20150205.brd")
		(comment 1 "Honey Badger (Wiwynn) / footprints 467-476 of 1509")
	)
	(layers
		(0 "F.Cu" signal "TOP")
		(4 "In1.Cu" signal "L2")
		(6 "In2.Cu" signal "L3")
		(8 "In3.Cu" signal "L4")
		(10 "In4.Cu" signal "L5")
		(12 "In5.Cu" signal "L6")
		(14 "In6.Cu" signal "L7")
		(16 "In7.Cu" signal "L8")
		(18 "In8.Cu" signal "L9")
		(20 "In9.Cu" signal "L10")
		(22 "In10.Cu" signal "L11")
		(2 "B.Cu" signal "BOTTOM")
		(9 "F.Adhes" user "F.Adhesive")
		(11 "B.Adhes" user "B.Adhesive")
		(13 "F.Paste" user "Package Geometry/Pastemask Top")
		(15 "B.Paste" user "Package Geometry/Pastemask Bottom")
		(5 "F.SilkS" user "Ref Des/Silkscreen Top")
		(7 "B.SilkS" user "Ref Des/Silkscreen Bottom")
		(1 "F.Mask" user "Board Geometry/Soldermask Top")
		(3 "B.Mask" user "Board Geometry/Soldermask Bottom")
		(17 "Dwgs.User" user "User.Drawings")
		(19 "Cmts.User" user "User.Comments")
		(21 "Eco1.User" user "User.Eco1")
		(23 "Eco2.User" user "User.Eco2")
		(25 "Edge.Cuts" user "Board Geometry/Outline")
		(27 "Margin" user)
		(31 "F.CrtYd" user "Package Geometry/Place Bound Top")
		(29 "B.CrtYd" user "Package Geometry/Place Bound Bottom")
		(35 "F.Fab" user "Ref Des/Assembly Top")
		(33 "B.Fab" user "Ref Des/Assembly Bottom")
	)
	(footprint ""
		(layer "F.Cu")
		(at 8.509 -60.96 90)
		(property "Reference" "C34"
			(at 0 0 90)
			(layer "F.SilkS")
			(hide yes)
			(effects
				(font
					(size 1.27 1.27)
				)
			)
		)
		(property "Value" "SCD1U16V2KX-3GP"
			(at 1.1811 -2.7051 90)
			(unlocked yes)
			(layer "F.Fab")
			(hide yes)
			(effects
				(font
					(size 1.016 1.016)
					(thickness 0.1524)
				)
			)
		)
		(property "Device Type" "C402H22"
			(at 1.1811 -4.2291 90)
			(unlocked yes)
			(layer "F.Fab")
			(hide yes)
			(effects
				(font
					(size 1.016 1.016)
					(thickness 0.1524)
				)
			)
		)
		(duplicate_pad_numbers_are_jumpers no)
		(fp_rect
			(start -0.381 0.7366)
			(end 0.381 -0.7366)
			(stroke
				(width 0)
				(type default)
			)
			(fill no)
			(layer "F.CrtYd")
		)
		(fp_rect
			(start -0.381 0.7366)
			(end 0.381 -0.7366)
			(stroke
				(width 0)
				(type default)
			)
			(fill no)
			(layer "F.Fab")
		)
		(pad "1" smd custom
			(at 0 -0.4572 90)
			(size 0.1143 0.1143)
			(layers "F.Cu" "F.Mask" "F.Paste")
			(net "P2E_CPU_NGFF_C_RX_DP14")
			(options
				(clearance outline)
				(anchor circle)
			)
			(primitives
				(gr_poly
					(pts
						(arc
							(start -0.254 -0.1778)
							(mid -0.239121 -0.213721)
							(end -0.2032 -0.2286)
						)
						(arc
							(start 0.2032 -0.2286)
							(mid 0.239121 -0.213721)
							(end 0.254 -0.1778)
						)
						(arc
							(start 0.254 0.1778)
							(mid 0.239121 0.213721)
							(end 0.2032 0.2286)
						)
						(arc
							(start -0.2032 0.2286)
							(mid -0.239121 0.213721)
							(end -0.254 0.1778)
						)
					)
					(width 0)
					(fill yes)
				)
			)
		)
		(pad "2" smd custom
			(at 0 0.4572 90)
			(size 0.1143 0.1143)
			(layers "F.Cu" "F.Mask" "F.Paste")
			(net "P2E_CPU_NGFF_RX_DP14")
			(options
				(clearance outline)
				(anchor circle)
			)
			(primitives
				(gr_poly
					(pts
						(arc
							(start -0.254 -0.1778)
							(mid -0.239121 -0.213721)
							(end -0.2032 -0.2286)
						)
						(arc
							(start 0.2032 -0.2286)
							(mid 0.239121 -0.213721)
							(end 0.254 -0.1778)
						)
						(arc
							(start 0.254 0.1778)
							(mid 0.239121 0.213721)
							(end 0.2032 0.2286)
						)
						(arc
							(start -0.2032 0.2286)
							(mid -0.239121 0.213721)
							(end -0.254 0.1778)
						)
					)
					(width 0)
					(fill yes)
				)
			)
		)
	)
	(footprint ""
		(layer "F.Cu")
		(at 25.8318 -37.465)
		(property "Reference" "PC77"
			(at 0 0 0)
			(layer "F.SilkS")
			(hide yes)
			(effects
				(font
					(size 1.27 1.27)
				)
			)
		)
		(property "Value" "SC100U6D3V6MX-GP"
			(at 0.0127 -3.4671 0)
			(unlocked yes)
			(layer "F.Fab")
			(hide yes)
			(effects
				(font
					(size 1.016 1.016)
					(thickness 0.1524)
				)
			)
		)
		(property "Device Type" "C1206H71"
			(at 0.0127 -4.9911 0)
			(unlocked yes)
			(layer "F.Fab")
			(hide yes)
			(effects
				(font
					(size 1.016 1.016)
					(thickness 0.1524)
				)
			)
		)
		(duplicate_pad_numbers_are_jumpers no)
		(fp_rect
			(start -1.0541 1.9812)
			(end 1.0541 -1.9812)
			(stroke
				(width 0)
				(type default)
			)
			(fill no)
			(layer "F.CrtYd")
		)
		(fp_rect
			(start -1.0541 1.9812)
			(end 1.0541 -1.9812)
			(stroke
				(width 0)
				(type default)
			)
			(fill no)
			(layer "F.Fab")
		)
		(pad "1" smd rect
			(at 0 -1.3462)
			(size 1.8542 1.016)
			(layers "F.Cu" "F.Mask" "F.Paste")
			(net "P3V3_STBY_OUT")
		)
		(pad "2" smd rect
			(at 0 1.3462)
			(size 1.8542 1.016)
			(layers "F.Cu" "F.Mask" "F.Paste")
			(net "GND")
		)
	)
	(footprint ""
		(layer "F.Cu")
		(at 182.499 -55.626 180)
		(property "Reference" "R201"
			(at 0 0 180)
			(layer "F.SilkS")
			(hide yes)
			(effects
				(font
					(size 1.27 1.27)
				)
			)
		)
		(property "Value" "0R2J-2-GP"
			(at 0.064008 -3.993896 180)
			(unlocked yes)
			(layer "F.Fab")
			(hide yes)
			(effects
				(font
					(size 1.016 1.016)
					(thickness 0.1524)
				)
			)
		)
		(property "Device Type" "R402H16"
			(at 0.064008 -5.517896 180)
			(unlocked yes)
			(layer "F.Fab")
			(hide yes)
			(effects
				(font
					(size 1.016 1.016)
					(thickness 0.1524)
				)
			)
		)
		(duplicate_pad_numbers_are_jumpers no)
		(fp_rect
			(start -0.381 0.8382)
			(end 0.381 -0.8382)
			(stroke
				(width 0)
				(type default)
			)
			(fill no)
			(layer "F.CrtYd")
		)
		(fp_rect
			(start -0.381 0.8382)
			(end 0.381 -0.8382)
			(stroke
				(width 0)
				(type default)
			)
			(fill no)
			(layer "F.Fab")
		)
		(pad "1" smd custom
			(at 0 -0.4318 180)
			(size 0.127 0.127)
			(layers "F.Cu" "F.Mask" "F.Paste")
			(net "PV_VDDR_VREF_A")
			(options
				(clearance outline)
				(anchor circle)
			)
			(primitives
				(gr_poly
					(pts
						(arc
							(start -0.2032 -0.2794)
							(mid -0.239121 -0.264521)
							(end -0.254 -0.2286)
						)
						(arc
							(start -0.254 0.2286)
							(mid -0.239121 0.264521)
							(end -0.2032 0.2794)
						)
						(arc
							(start 0.2032 0.2794)
							(mid 0.239121 0.264521)
							(end 0.254 0.2286)
						)
						(arc
							(start 0.254 -0.2286)
							(mid 0.239121 -0.264521)
							(end 0.2032 -0.2794)
						)
					)
					(width 0)
					(fill yes)
				)
			)
		)
		(pad "2" smd custom
			(at 0 0.4318 180)
			(size 0.127 0.127)
			(layers "F.Cu" "F.Mask" "F.Paste")
			(net "DDR3_M_A_VREF_DQ0")
			(options
				(clearance outline)
				(anchor circle)
			)
			(primitives
				(gr_poly
					(pts
						(arc
							(start -0.2032 -0.2794)
							(mid -0.239121 -0.264521)
							(end -0.254 -0.2286)
						)
						(arc
							(start -0.254 0.2286)
							(mid -0.239121 0.264521)
							(end -0.2032 0.2794)
						)
						(arc
							(start 0.2032 0.2794)
							(mid 0.239121 0.264521)
							(end 0.254 0.2286)
						)
						(arc
							(start 0.254 -0.2286)
							(mid 0.239121 -0.264521)
							(end 0.2032 -0.2794)
						)
					)
					(width 0)
					(fill yes)
				)
			)
		)
	)
	(footprint ""
		(layer "F.Cu")
		(at 60.1218 -51.8922)
		(property "Reference" "PC112"
			(at 0 0 0)
			(layer "F.SilkS")
			(hide yes)
			(effects
				(font
					(size 1.27 1.27)
				)
			)
		)
		(property "Value" "SC22U6D3V5MX-2GP"
			(at 0 -4.9022 0)
			(unlocked yes)
			(layer "F.Fab")
			(hide yes)
			(effects
				(font
					(size 1.016 1.016)
					(thickness 0.1524)
				)
			)
		)
		(property "Device Type" "C805H58"
			(at 0 -6.8072 0)
			(unlocked yes)
			(layer "F.Fab")
			(hide yes)
			(effects
				(font
					(size 1.016 1.016)
					(thickness 0.1524)
				)
			)
		)
		(duplicate_pad_numbers_are_jumpers no)
		(fp_line
			(start 0.6096 0)
			(end -0.6096 0)
			(stroke
				(width 0.3048)
				(type default)
			)
			(layer "F.SilkS")
		)
		(fp_poly
			(pts
				(xy -0.9017 1.4351) (xy 0.9017 1.4351) (xy 0.9017 -1.4351) (xy -0.9017 -1.4351)
			)
			(stroke
				(width 0)
				(type default)
			)
			(fill no)
			(layer "F.CrtYd")
		)
		(fp_poly
			(pts
				(xy 0.9017 1.4351) (xy 0.9017 -1.4351) (xy -0.9017 -1.4351) (xy -0.9017 1.4351)
			)
			(stroke
				(width 0)
				(type default)
			)
			(fill no)
			(layer "F.Fab")
		)
		(pad "1" smd rect
			(at 0 -0.8382)
			(size 1.5494 0.9398)
			(layers "F.Cu" "F.Mask" "F.Paste")
			(net "P1V0_STBY_VOUT")
		)
		(pad "2" smd rect
			(at 0 0.8382)
			(size 1.5494 0.9398)
			(layers "F.Cu" "F.Mask" "F.Paste")
			(net "GND")
		)
	)
	(footprint ""
		(layer "F.Cu")
		(at 194.31 -37.0586 -90)
		(property "Reference" "PR133"
			(at 0 0 270)
			(layer "F.SilkS")
			(hide yes)
			(effects
				(font
					(size 1.27 1.27)
				)
			)
		)
		(property "Value" "0R2J-2-GP"
			(at 1.7907 -1.1176 270)
			(unlocked yes)
			(layer "F.Fab")
			(hide yes)
			(effects
				(font
					(size 1.016 1.016)
					(thickness 0.1524)
				)
			)
		)
		(property "Device Type" "R402H16"
			(at 1.7907 -2.6416 270)
			(unlocked yes)
			(layer "F.Fab")
			(hide yes)
			(effects
				(font
					(size 1.016 1.016)
					(thickness 0.1524)
				)
			)
		)
		(duplicate_pad_numbers_are_jumpers no)
		(fp_rect
			(start -0.381 0.8382)
			(end 0.381 -0.8382)
			(stroke
				(width 0)
				(type default)
			)
			(fill no)
			(layer "F.CrtYd")
		)
		(fp_rect
			(start -0.381 0.8382)
			(end 0.381 -0.8382)
			(stroke
				(width 0)
				(type default)
			)
			(fill no)
			(layer "F.Fab")
		)
		(pad "1" smd custom
			(at 0 -0.4318 270)
			(size 0.127 0.127)
			(layers "F.Cu" "F.Mask" "F.Paste")
			(net "VDDR_5VBIAS")
			(options
				(clearance outline)
				(anchor circle)
			)
			(primitives
				(gr_poly
					(pts
						(arc
							(start -0.2032 -0.2794)
							(mid -0.239121 -0.264521)
							(end -0.254 -0.2286)
						)
						(arc
							(start -0.254 0.2286)
							(mid -0.239121 0.264521)
							(end -0.2032 0.2794)
						)
						(arc
							(start 0.2032 0.2794)
							(mid 0.239121 0.264521)
							(end 0.254 0.2286)
						)
						(arc
							(start 0.254 -0.2286)
							(mid 0.239121 -0.264521)
							(end 0.2032 -0.2794)
						)
					)
					(width 0)
					(fill yes)
				)
			)
		)
		(pad "2" smd custom
			(at 0 0.4318 270)
			(size 0.127 0.127)
			(layers "F.Cu" "F.Mask" "F.Paste")
			(net "VR_PVDDR_A_VDDP")
			(options
				(clearance outline)
				(anchor circle)
			)
			(primitives
				(gr_poly
					(pts
						(arc
							(start -0.2032 -0.2794)
							(mid -0.239121 -0.264521)
							(end -0.254 -0.2286)
						)
						(arc
							(start -0.254 0.2286)
							(mid -0.239121 0.264521)
							(end -0.2032 0.2794)
						)
						(arc
							(start 0.2032 0.2794)
							(mid 0.239121 0.264521)
							(end 0.254 0.2286)
						)
						(arc
							(start 0.254 -0.2286)
							(mid 0.239121 -0.264521)
							(end 0.2032 -0.2794)
						)
					)
					(width 0)
					(fill yes)
				)
			)
		)
	)
	(footprint ""
		(layer "F.Cu")
		(at 135.763 -52.959)
		(property "Reference" "PC53"
			(at 0 0 0)
			(layer "F.SilkS")
			(hide yes)
			(effects
				(font
					(size 1.27 1.27)
				)
			)
		)
		(property "Value" "SCD1U16V2KX-3GP"
			(at 1.1811 -2.7051 0)
			(unlocked yes)
			(layer "F.Fab")
			(hide yes)
			(effects
				(font
					(size 1.016 1.016)
					(thickness 0.1524)
				)
			)
		)
		(property "Device Type" "C402H22"
			(at 1.1811 -4.2291 0)
			(unlocked yes)
			(layer "F.Fab")
			(hide yes)
			(effects
				(font
					(size 1.016 1.016)
					(thickness 0.1524)
				)
			)
		)
		(duplicate_pad_numbers_are_jumpers no)
		(fp_rect
			(start -0.381 0.7366)
			(end 0.381 -0.7366)
			(stroke
				(width 0)
				(type default)
			)
			(fill no)
			(layer "F.CrtYd")
		)
		(fp_rect
			(start -0.381 0.7366)
			(end 0.381 -0.7366)
			(stroke
				(width 0)
				(type default)
			)
			(fill no)
			(layer "F.Fab")
		)
		(pad "1" smd custom
			(at 0 -0.4572)
			(size 0.1143 0.1143)
			(layers "F.Cu" "F.Mask" "F.Paste")
			(net "PV_VTT_DDR_REFO")
			(options
				(clearance outline)
				(anchor circle)
			)
			(primitives
				(gr_poly
					(pts
						(arc
							(start -0.254 -0.1778)
							(mid -0.239121 -0.213721)
							(end -0.2032 -0.2286)
						)
						(arc
							(start 0.2032 -0.2286)
							(mid 0.239121 -0.213721)
							(end 0.254 -0.1778)
						)
						(arc
							(start 0.254 0.1778)
							(mid 0.239121 0.213721)
							(end 0.2032 0.2286)
						)
						(arc
							(start -0.2032 0.2286)
							(mid -0.239121 0.213721)
							(end -0.254 0.1778)
						)
					)
					(width 0)
					(fill yes)
				)
			)
		)
		(pad "2" smd custom
			(at 0 0.4572)
			(size 0.1143 0.1143)
			(layers "F.Cu" "F.Mask" "F.Paste")
			(net "GND")
			(options
				(clearance outline)
				(anchor circle)
			)
			(primitives
				(gr_poly
					(pts
						(arc
							(start -0.254 -0.1778)
							(mid -0.239121 -0.213721)
							(end -0.2032 -0.2286)
						)
						(arc
							(start 0.2032 -0.2286)
							(mid 0.239121 -0.213721)
							(end 0.254 -0.1778)
						)
						(arc
							(start 0.254 0.1778)
							(mid 0.239121 0.213721)
							(end 0.2032 0.2286)
						)
						(arc
							(start -0.2032 0.2286)
							(mid -0.239121 0.213721)
							(end -0.254 0.1778)
						)
					)
					(width 0)
					(fill yes)
				)
			)
		)
	)
	(footprint ""
		(layer "F.Cu")
		(at 30.734 -66.294)
		(property "Reference" "PL3"
			(at 0 0 0)
			(layer "F.SilkS")
			(hide yes)
			(effects
				(font
					(size 1.27 1.27)
				)
			)
		)
		(property "Value" "COIL-D22UH-GP"
			(at -3.302 0.0508 0)
			(unlocked yes)
			(layer "F.Fab")
			(hide yes)
			(effects
				(font
					(size 1.016 1.016)
					(thickness 0.1524)
				)
			)
		)
		(property "Device Type" "L4540-1222H79"
			(at -3.302 -1.4732 0)
			(unlocked yes)
			(layer "F.Fab")
			(hide yes)
			(effects
				(font
					(size 1.016 1.016)
					(thickness 0.1524)
				)
			)
		)
		(duplicate_pad_numbers_are_jumpers no)
		(fp_rect
			(start -2.2606 2.7559)
			(end 2.2606 -2.7559)
			(stroke
				(width 0)
				(type default)
			)
			(fill no)
			(layer "F.CrtYd")
		)
		(fp_rect
			(start -2.2606 2.7559)
			(end 2.2606 -2.7559)
			(stroke
				(width 0)
				(type default)
			)
			(fill no)
			(layer "F.Fab")
		)
		(pad "1" smd rect
			(at 0 -1.710436)
			(size 2.4638 1.8288)
			(layers "F.Cu" "F.Mask" "F.Paste")
			(net "P12V")
		)
		(pad "2" smd rect
			(at 0 1.710436)
			(size 2.4638 1.8288)
			(layers "F.Cu" "F.Mask" "F.Paste")
			(net "VR_FET_SW_P12V_PVCCP_PVNN")
		)
	)
	(footprint ""
		(layer "F.Cu")
		(at 167.894 -12.955778 180)
		(property "Reference" "C372"
			(at 0 0 180)
			(layer "F.SilkS")
			(hide yes)
			(effects
				(font
					(size 1.27 1.27)
				)
			)
		)
		(property "Value" "SC47U6D3V5MX-1-GP"
			(at 0 -4.9022 180)
			(unlocked yes)
			(layer "F.Fab")
			(hide yes)
			(effects
				(font
					(size 1.016 1.016)
					(thickness 0.1524)
				)
			)
		)
		(property "Device Type" "C805H54"
			(at 0 -6.8072 180)
			(unlocked yes)
			(layer "F.Fab")
			(hide yes)
			(effects
				(font
					(size 1.016 1.016)
					(thickness 0.1524)
				)
			)
		)
		(duplicate_pad_numbers_are_jumpers no)
		(fp_line
			(start 0.6096 0)
			(end -0.6096 0)
			(stroke
				(width 0.3048)
				(type default)
			)
			(layer "F.SilkS")
		)
		(fp_poly
			(pts
				(xy -0.9017 1.4351) (xy 0.9017 1.4351) (xy 0.9017 -1.4351) (xy -0.9017 -1.4351)
			)
			(stroke
				(width 0)
				(type default)
			)
			(fill no)
			(layer "F.CrtYd")
		)
		(fp_poly
			(pts
				(xy 0.9017 1.4351) (xy 0.9017 -1.4351) (xy -0.9017 -1.4351) (xy -0.9017 1.4351)
			)
			(stroke
				(width 0)
				(type default)
			)
			(fill no)
			(layer "F.Fab")
		)
		(pad "1" smd rect
			(at 0 -0.8382 180)
			(size 1.5494 0.9398)
			(layers "F.Cu" "F.Mask" "F.Paste")
			(net "PV_VDDR")
		)
		(pad "2" smd rect
			(at 0 0.8382 180)
			(size 1.5494 0.9398)
			(layers "F.Cu" "F.Mask" "F.Paste")
			(net "GND")
		)
	)
	(footprint ""
		(layer "F.Cu")
		(at 117.094 -68.326 180)
		(property "Reference" "R16"
			(at 0 0 180)
			(layer "F.SilkS")
			(hide yes)
			(effects
				(font
					(size 1.27 1.27)
				)
			)
		)
		(property "Value" "33R2F-3-GP"
			(at 0.064008 -3.993896 180)
			(unlocked yes)
			(layer "F.Fab")
			(hide yes)
			(effects
				(font
					(size 1.016 1.016)
					(thickness 0.1524)
				)
			)
		)
		(property "Device Type" "R402H16"
			(at 0.064008 -5.517896 180)
			(unlocked yes)
			(layer "F.Fab")
			(hide yes)
			(effects
				(font
					(size 1.016 1.016)
					(thickness 0.1524)
				)
			)
		)
		(duplicate_pad_numbers_are_jumpers no)
		(fp_rect
			(start -0.381 0.8382)
			(end 0.381 -0.8382)
			(stroke
				(width 0)
				(type default)
			)
			(fill no)
			(layer "F.CrtYd")
		)
		(fp_rect
			(start -0.381 0.8382)
			(end 0.381 -0.8382)
			(stroke
				(width 0)
				(type default)
			)
			(fill no)
			(layer "F.Fab")
		)
		(pad "1" smd custom
			(at 0 -0.4318 180)
			(size 0.127 0.127)
			(layers "F.Cu" "F.Mask" "F.Paste")
			(net "CLK_GEN_OUT_R")
			(options
				(clearance outline)
				(anchor circle)
			)
			(primitives
				(gr_poly
					(pts
						(arc
							(start -0.2032 -0.2794)
							(mid -0.239121 -0.264521)
							(end -0.254 -0.2286)
						)
						(arc
							(start -0.254 0.2286)
							(mid -0.239121 0.264521)
							(end -0.2032 0.2794)
						)
						(arc
							(start 0.2032 0.2794)
							(mid 0.239121 0.264521)
							(end 0.254 0.2286)
						)
						(arc
							(start 0.254 -0.2286)
							(mid 0.239121 -0.264521)
							(end 0.2032 -0.2794)
						)
					)
					(width 0)
					(fill yes)
				)
			)
		)
		(pad "2" smd custom
			(at 0 0.4318 180)
			(size 0.127 0.127)
			(layers "F.Cu" "F.Mask" "F.Paste")
			(net "CLK_GEN_OUT")
			(options
				(clearance outline)
				(anchor circle)
			)
			(primitives
				(gr_poly
					(pts
						(arc
							(start -0.2032 -0.2794)
							(mid -0.239121 -0.264521)
							(end -0.254 -0.2286)
						)
						(arc
							(start -0.254 0.2286)
							(mid -0.239121 0.264521)
							(end -0.2032 0.2794)
						)
						(arc
							(start 0.2032 0.2794)
							(mid 0.239121 0.264521)
							(end 0.254 0.2286)
						)
						(arc
							(start 0.254 -0.2286)
							(mid 0.239121 -0.264521)
							(end 0.2032 -0.2794)
						)
					)
					(width 0)
					(fill yes)
				)
			)
		)
	)
	(footprint ""
		(layer "F.Cu")
		(at 98.298 -68.58 180)
		(property "Reference" "TP3"
			(at 0 0 180)
			(layer "F.SilkS")
			(hide yes)
			(effects
				(font
					(size 1.27 1.27)
				)
			)
		)
		(property "Value" "TPAD28-1-GP-U"
			(at 0.0508 -1.9304 180)
			(unlocked yes)
			(layer "F.Fab")
			(hide yes)
			(effects
				(font
					(size 1.016 1.016)
					(thickness 0.1524)
				)
			)
		)
		(property "Device Type" "TPAD28-1-U"
			(at 0.0508 -3.4544 180)
			(unlocked yes)
			(layer "F.Fab")
			(hide yes)
			(effects
				(font
					(size 1.016 1.016)
					(thickness 0.1524)
				)
			)
		)
		(duplicate_pad_numbers_are_jumpers no)
		(fp_poly
			(pts
				(arc
					(start -0.3556 0)
					(mid 0.3556 0)
					(end -0.3556 0)
				)
			)
			(stroke
				(width 0)
				(type default)
			)
			(fill no)
			(layer "F.CrtYd")
		)
		(fp_poly
			(pts
				(arc
					(start -0.9525 0)
					(mid 0.9525 0)
					(end -0.9525 0)
				)
			)
			(stroke
				(width 0)
				(type default)
			)
			(fill no)
			(layer "F.Fab")
		)
		(pad "1" smd circle
			(at 0 0 180)
			(size 0.7112 0.7112)
			(layers "F.Cu" "F.Mask" "F.Paste")
			(net "TP_BGND")
		)
	)
)
